(kicad_pcb
	(version 20260206)
	(generator "pcbnew")
	(generator_version "10.0")
	(general
		(thickness 1.6)
		(legacy_teardrops no)
	)
	(paper "A4")
	(title_block
		(title "01162023_DA0F0TEBIF0_F0T_Expander_BD_F_brd_V02_OCP.brd")
		(comment 1 "Grand Teton / footprints 8513-8518 of 9728")
	)
	(layers
		(0 "F.Cu" signal "TOP")
		(4 "In1.Cu" signal "GND")
		(6 "In2.Cu" signal "VCC")
		(8 "In3.Cu" signal "VCC1")
		(10 "In4.Cu" signal "GND1")
		(12 "In5.Cu" signal "IN1")
		(14 "In6.Cu" signal "GND2")
		(16 "In7.Cu" signal "IN2")
		(18 "In8.Cu" signal "GND3")
		(20 "In9.Cu" signal "IN3")
		(22 "In10.Cu" signal "GND4")
		(24 "In11.Cu" signal "IN4")
		(26 "In12.Cu" signal "GND5")
		(28 "In13.Cu" signal "IN5")
		(30 "In14.Cu" signal "GND6")
		(32 "In15.Cu" signal "IN6")
		(34 "In16.Cu" signal "GND7")
		(2 "B.Cu" signal "BOTTOM")
		(9 "F.Adhes" user "F.Adhesive")
		(11 "B.Adhes" user "B.Adhesive")
		(13 "F.Paste" user "Package Geometry/Pastemask Top")
		(15 "B.Paste" user "Package Geometry/Pastemask Bottom")
		(5 "F.SilkS" user "Ref Des/Silkscreen Top")
		(7 "B.SilkS" user "Ref Des/Silkscreen Bottom")
		(1 "F.Mask" user "Board Geometry/Soldermask Top")
		(3 "B.Mask" user "Board Geometry/Soldermask Bottom")
		(17 "Dwgs.User" user "User.Drawings")
		(19 "Cmts.User" user "User.Comments")
		(21 "Eco1.User" user "User.Eco1")
		(23 "Eco2.User" user "User.Eco2")
		(25 "Edge.Cuts" user "Board Geometry/Outline")
		(27 "Margin" user)
		(31 "F.CrtYd" user "Package Geometry/Place Bound Top")
		(29 "B.CrtYd" user "Package Geometry/Place Bound Bottom")
		(35 "F.Fab" user "Ref Des/Assembly Top")
		(33 "B.Fab" user "Ref Des/Assembly Bottom")
	)
	(footprint ""
		(layer "B.Cu")
		(at 314.119768 10.649712)
		(property "Reference" "DE16T_4"
			(at 2.796032 3.067558 0)
			(unlocked yes)
			(layer "B.SilkS")
			(effects
				(font
					(size 0.7874 0.5842)
					(thickness 0.1524)
				)
				(justify left mirror)
			)
		)
		(property "Value" ""
			(at 0 0 0)
			(layer "B.Fab")
			(effects
				(font
					(size 1.27 1.27)
				)
				(justify mirror)
			)
		)
		(duplicate_pad_numbers_are_jumpers no)
		(fp_line
			(start -1.2192 -2.1082)
			(end -1.2192 2.1082)
			(stroke
				(width 0.1524)
				(type default)
			)
			(layer "B.SilkS")
		)
		(fp_line
			(start -1.2192 2.1082)
			(end 1.2192 2.1082)
			(stroke
				(width 0.1524)
				(type default)
			)
			(layer "B.SilkS")
		)
		(fp_line
			(start 1.2192 -2.1082)
			(end -1.2192 -2.1082)
			(stroke
				(width 0.1524)
				(type default)
			)
			(layer "B.SilkS")
		)
		(fp_line
			(start 1.2192 2.1082)
			(end 1.2192 -2.1082)
			(stroke
				(width 0.1524)
				(type default)
			)
			(layer "B.SilkS")
		)
		(pad "" np_thru_hole circle
			(at -3.4671 -1.27 270)
			(size 1.0414 1.0414)
			(drill 1.0414)
			(layers "*.Cu" "*.Mask")
			(clearance 0.381)
			(thermal_gap 0.381)
		)
		(pad "" np_thru_hole circle
			(at -3.4671 1.27 270)
			(size 1.0414 1.0414)
			(drill 1.0414)
			(layers "*.Cu" "*.Mask")
			(clearance 0.381)
			(thermal_gap 0.381)
		)
		(pad "" np_thru_hole circle
			(at 2.8829 -1.27 270)
			(size 1.0414 1.0414)
			(drill 1.0414)
			(layers "*.Cu" "*.Mask")
			(clearance 0.381)
			(thermal_gap 0.381)
		)
		(pad "" np_thru_hole circle
			(at 2.8829 1.27 270)
			(size 1.0414 1.0414)
			(drill 1.0414)
			(layers "*.Cu" "*.Mask")
			(clearance 0.381)
			(thermal_gap 0.381)
		)
		(pad "1" smd rect
			(at -0.8255 -0.249936 270)
			(size 0.3048 0.508)
			(layers "B.Cu" "B.Mask" "B.Paste")
			(net "85_10INCH_IN6_DN")
		)
		(pad "2" smd rect
			(at -0.8255 0.249936 270)
			(size 0.3048 0.508)
			(layers "B.Cu" "B.Mask" "B.Paste")
			(net "85_10INCH_IN6_DP")
		)
		(pad "3" smd circle
			(at 0 0 180)
			(size 0 0)
			(layers "B.Cu" "B.Mask" "B.Paste")
			(net "COUPON_GND2")
		)
		(zone
			(layers "F.Cu" "B.Cu" "In1.Cu" "In2.Cu" "In3.Cu" "In4.Cu" "In5.Cu" "In6.Cu"
				"In7.Cu" "In8.Cu" "In9.Cu" "In10.Cu" "In11.Cu" "In12.Cu" "In13.Cu" "In14.Cu"
				"In15.Cu" "In16.Cu"
			)
			(hatch none 0.5)
			(connect_pads
				(clearance 0)
			)
			(min_thickness 0.25)
			(keepout
				(tracks not_allowed)
				(vias allowed)
				(pads allowed)
				(copperpour not_allowed)
				(footprints allowed)
			)
			(placement
				(enabled no)
				(sheetname "")
			)
			(fill
				(thermal_gap 0.5)
				(thermal_bridge_width 0.5)
				(island_removal_mode 0)
			)
			(polygon
				(pts
					(arc
						(start 311.579768 9.379712)
						(mid 309.725568 9.379712)
						(end 311.579768 9.379712)
					)
				)
			)
		)
		(zone
			(layers "F.Cu" "B.Cu" "In1.Cu" "In2.Cu" "In3.Cu" "In4.Cu" "In5.Cu" "In6.Cu"
				"In7.Cu" "In8.Cu" "In9.Cu" "In10.Cu" "In11.Cu" "In12.Cu" "In13.Cu" "In14.Cu"
				"In15.Cu" "In16.Cu"
			)
			(hatch none 0.5)
			(connect_pads
				(clearance 0)
			)
			(min_thickness 0.25)
			(keepout
				(tracks not_allowed)
				(vias allowed)
				(pads allowed)
				(copperpour not_allowed)
				(footprints allowed)
			)
			(placement
				(enabled no)
				(sheetname "")
			)
			(fill
				(thermal_gap 0.5)
				(thermal_bridge_width 0.5)
				(island_removal_mode 0)
			)
			(polygon
				(pts
					(arc
						(start 311.579768 11.919712)
						(mid 309.725568 11.919712)
						(end 311.579768 11.919712)
					)
				)
			)
		)
		(zone
			(layers "F.Cu" "B.Cu" "In1.Cu" "In2.Cu" "In3.Cu" "In4.Cu" "In5.Cu" "In6.Cu"
				"In7.Cu" "In8.Cu" "In9.Cu" "In10.Cu" "In11.Cu" "In12.Cu" "In13.Cu" "In14.Cu"
				"In15.Cu" "In16.Cu"
			)
			(hatch none 0.5)
			(connect_pads
				(clearance 0)
			)
			(min_thickness 0.25)
			(keepout
				(tracks not_allowed)
				(vias allowed)
				(pads allowed)
				(copperpour not_allowed)
				(footprints allowed)
			)
			(placement
				(enabled no)
				(sheetname "")
			)
			(fill
				(thermal_gap 0.5)
				(thermal_bridge_width 0.5)
				(island_removal_mode 0)
			)
			(polygon
				(pts
					(arc
						(start 317.929768 9.379712)
						(mid 316.075568 9.379712)
						(end 317.929768 9.379712)
					)
				)
			)
		)
		(zone
			(layers "F.Cu" "B.Cu" "In1.Cu" "In2.Cu" "In3.Cu" "In4.Cu" "In5.Cu" "In6.Cu"
				"In7.Cu" "In8.Cu" "In9.Cu" "In10.Cu" "In11.Cu" "In12.Cu" "In13.Cu" "In14.Cu"
				"In15.Cu" "In16.Cu"
			)
			(hatch none 0.5)
			(connect_pads
				(clearance 0)
			)
			(min_thickness 0.25)
			(keepout
				(tracks not_allowed)
				(vias allowed)
				(pads allowed)
				(copperpour not_allowed)
				(footprints allowed)
			)
			(placement
				(enabled no)
				(sheetname "")
			)
			(fill
				(thermal_gap 0.5)
				(thermal_bridge_width 0.5)
				(island_removal_mode 0)
			)
			(polygon
				(pts
					(arc
						(start 317.929768 11.919712)
						(mid 316.075568 11.919712)
						(end 317.929768 11.919712)
					)
				)
			)
		)
		(zone
			(layer "B.Cu")
			(hatch none 0.5)
			(connect_pads
				(clearance 0)
			)
			(min_thickness 0.25)
			(keepout
				(tracks not_allowed)
				(vias allowed)
				(pads allowed)
				(copperpour not_allowed)
				(footprints allowed)
			)
			(placement
				(enabled no)
				(sheetname "")
			)
			(fill
				(thermal_gap 0.5)
				(thermal_bridge_width 0.5)
				(island_removal_mode 0)
			)
			(polygon
				(pts
					(xy 313.002168 10.101072) (xy 313.002168 10.196576) (xy 313.599068 10.196576) (xy 313.599068 10.602976)
					(xy 313.002168 10.602976) (xy 313.002168 10.696448) (xy 313.599068 10.696448) (xy 313.599068 11.102848)
					(xy 313.002168 11.102848) (xy 313.002168 11.198352) (xy 313.700668 11.198352) (xy 313.700668 10.101072)
				)
			)
		)
	)
	(footprint ""
		(layer "B.Cu")
		(at 175.260762 -305.557936 -90)
		(property "Reference" "C3119"
			(at 0 0 90)
			(layer "B.SilkS")
			(hide yes)
			(effects
				(font
					(size 1.27 1.27)
				)
				(justify mirror)
			)
		)
		(property "Value" ""
			(at 0 0 90)
			(layer "B.Fab")
			(effects
				(font
					(size 1.27 1.27)
				)
				(justify mirror)
			)
		)
		(duplicate_pad_numbers_are_jumpers no)
		(fp_line
			(start -1.2954 0.5842)
			(end 1.2954 0.5842)
			(stroke
				(width 0.1524)
				(type default)
			)
			(layer "B.SilkS")
		)
		(fp_line
			(start 1.2954 0.5842)
			(end 1.2954 -0.5842)
			(stroke
				(width 0.1524)
				(type default)
			)
			(layer "B.SilkS")
		)
		(fp_line
			(start -1.2954 -0.5842)
			(end -1.2954 0.5842)
			(stroke
				(width 0.1524)
				(type default)
			)
			(layer "B.SilkS")
		)
		(fp_line
			(start 1.2954 -0.5842)
			(end -1.2954 -0.5842)
			(stroke
				(width 0.1524)
				(type default)
			)
			(layer "B.SilkS")
		)
		(fp_line
			(start -0.8636 0.4572)
			(end 0.8636 0.4572)
			(stroke
				(width 0.1)
				(type default)
			)
			(layer "B.Fab")
		)
		(fp_line
			(start 0.8636 0.4572)
			(end 0.8636 0.4064)
			(stroke
				(width 0.1)
				(type default)
			)
			(layer "B.Fab")
		)
		(fp_line
			(start -1.1938 0.4064)
			(end -0.8636 0.4064)
			(stroke
				(width 0.1)
				(type default)
			)
			(layer "B.Fab")
		)
		(fp_line
			(start -0.8636 0.4064)
			(end -0.8636 0.4572)
			(stroke
				(width 0.1)
				(type default)
			)
			(layer "B.Fab")
		)
		(fp_line
			(start 0.8636 0.4064)
			(end 1.1938 0.4064)
			(stroke
				(width 0.1)
				(type default)
			)
			(layer "B.Fab")
		)
		(fp_line
			(start 1.1938 0.4064)
			(end 1.1938 -0.4064)
			(stroke
				(width 0.1)
				(type default)
			)
			(layer "B.Fab")
		)
		(fp_line
			(start -1.1938 -0.4064)
			(end -1.1938 0.4064)
			(stroke
				(width 0.1)
				(type default)
			)
			(layer "B.Fab")
		)
		(fp_line
			(start -0.8636 -0.4064)
			(end -1.1938 -0.4064)
			(stroke
				(width 0.1)
				(type default)
			)
			(layer "B.Fab")
		)
		(fp_line
			(start 0.8636 -0.4064)
			(end 0.8636 -0.4572)
			(stroke
				(width 0.1)
				(type default)
			)
			(layer "B.Fab")
		)
		(fp_line
			(start 1.1938 -0.4064)
			(end 0.8636 -0.4064)
			(stroke
				(width 0.1)
				(type default)
			)
			(layer "B.Fab")
		)
		(fp_line
			(start -0.8636 -0.4572)
			(end -0.8636 -0.4064)
			(stroke
				(width 0.1)
				(type default)
			)
			(layer "B.Fab")
		)
		(fp_line
			(start 0.8636 -0.4572)
			(end -0.8636 -0.4572)
			(stroke
				(width 0.1)
				(type default)
			)
			(layer "B.Fab")
		)
		(pad "1" smd rect
			(at 0.7366 0 180)
			(size 0.7112 0.8128)
			(layers "B.Cu" "B.Mask" "B.Paste")
			(net "P1V25_SERDES_VDDPLL_PEX1")
		)
		(pad "2" smd rect
			(at -0.7366 0 180)
			(size 0.7112 0.8128)
			(layers "B.Cu" "B.Mask" "B.Paste")
			(net "GND")
		)
	)
	(footprint ""
		(layer "B.Cu")
		(at 387.999986 -288.774886 -90)
		(property "Reference" "R3490"
			(at 0 0 90)
			(layer "B.SilkS")
			(hide yes)
			(effects
				(font
					(size 1.27 1.27)
				)
				(justify mirror)
			)
		)
		(property "Value" ""
			(at 0 0 90)
			(layer "B.Fab")
			(effects
				(font
					(size 1.27 1.27)
				)
				(justify mirror)
			)
		)
		(duplicate_pad_numbers_are_jumpers no)
		(fp_line
			(start -0.7874 0.4064)
			(end 0.7874 0.4064)
			(stroke
				(width 0.1524)
				(type default)
			)
			(layer "B.SilkS")
		)
		(fp_line
			(start 0.7874 0.4064)
			(end 0.7874 -0.4064)
			(stroke
				(width 0.1524)
				(type default)
			)
			(layer "B.SilkS")
		)
		(fp_line
			(start -0.7874 -0.4064)
			(end -0.7874 0.4064)
			(stroke
				(width 0.1524)
				(type default)
			)
			(layer "B.SilkS")
		)
		(fp_line
			(start 0.7874 -0.4064)
			(end -0.7874 -0.4064)
			(stroke
				(width 0.1524)
				(type default)
			)
			(layer "B.SilkS")
		)
		(fp_line
			(start -0.67945 0.3048)
			(end -0.120396 0.3048)
			(stroke
				(width 0.1)
				(type default)
			)
			(layer "B.Fab")
		)
		(fp_line
			(start -0.120396 0.3048)
			(end -0.120396 0.2794)
			(stroke
				(width 0.1)
				(type default)
			)
			(layer "B.Fab")
		)
		(fp_line
			(start 0.12065 0.3048)
			(end 0.67945 0.3048)
			(stroke
				(width 0.1)
				(type default)
			)
			(layer "B.Fab")
		)
		(fp_line
			(start 0.67945 0.3048)
			(end 0.67945 -0.305054)
			(stroke
				(width 0.1)
				(type default)
			)
			(layer "B.Fab")
		)
		(fp_line
			(start -0.120396 0.2794)
			(end 0.12065 0.2794)
			(stroke
				(width 0.1)
				(type default)
			)
			(layer "B.Fab")
		)
		(fp_line
			(start 0.12065 0.2794)
			(end 0.12065 0.3048)
			(stroke
				(width 0.1)
				(type default)
			)
			(layer "B.Fab")
		)
		(fp_line
			(start -0.12065 -0.2794)
			(end -0.12065 -0.3048)
			(stroke
				(width 0.1)
				(type default)
			)
			(layer "B.Fab")
		)
		(fp_line
			(start 0.12065 -0.2794)
			(end -0.12065 -0.2794)
			(stroke
				(width 0.1)
				(type default)
			)
			(layer "B.Fab")
		)
		(fp_line
			(start -0.67945 -0.3048)
			(end -0.67945 0.3048)
			(stroke
				(width 0.1)
				(type default)
			)
			(layer "B.Fab")
		)
		(fp_line
			(start -0.12065 -0.3048)
			(end -0.67945 -0.3048)
			(stroke
				(width 0.1)
				(type default)
			)
			(layer "B.Fab")
		)
		(fp_line
			(start 0.12065 -0.305054)
			(end 0.12065 -0.2794)
			(stroke
				(width 0.1)
				(type default)
			)
			(layer "B.Fab")
		)
		(fp_line
			(start 0.67945 -0.305054)
			(end 0.12065 -0.305054)
			(stroke
				(width 0.1)
				(type default)
			)
			(layer "B.Fab")
		)
		(pad "1" smd circle
			(at 0.40005 0 90)
			(size 0 0)
			(layers "B.Cu" "B.Mask" "B.Paste")
			(net "SPI_PEX3_SDIO3_R")
		)
		(pad "2" smd circle
			(at -0.40005 0 90)
			(size 0 0)
			(layers "B.Cu" "B.Mask" "B.Paste")
			(net "SPI_PEX3_SDIO3")
		)
	)
	(footprint ""
		(layer "B.Cu")
		(at 56.324754 -286.399732 90)
		(property "Reference" "C2957"
			(at 0 0 90)
			(layer "B.SilkS")
			(hide yes)
			(effects
				(font
					(size 1.27 1.27)
				)
				(justify mirror)
			)
		)
		(property "Value" ""
			(at 0 0 90)
			(layer "B.Fab")
			(effects
				(font
					(size 1.27 1.27)
				)
				(justify mirror)
			)
		)
		(duplicate_pad_numbers_are_jumpers no)
		(fp_line
			(start 0.299974 -0.150114)
			(end -0.299974 -0.150114)
			(stroke
				(width 0.1)
				(type default)
			)
			(layer "B.Fab")
		)
		(fp_line
			(start -0.299974 -0.150114)
			(end -0.299974 0.150114)
			(stroke
				(width 0.1)
				(type default)
			)
			(layer "B.Fab")
		)
		(fp_line
			(start 0.299974 0.150114)
			(end 0.299974 -0.150114)
			(stroke
				(width 0.1)
				(type default)
			)
			(layer "B.Fab")
		)
		(fp_line
			(start -0.299974 0.150114)
			(end 0.299974 0.150114)
			(stroke
				(width 0.1)
				(type default)
			)
			(layer "B.Fab")
		)
		(pad "1" smd rect
			(at 0.2667 0 270)
			(size 0.3048 0.381)
			(layers "B.Cu" "B.Mask" "B.Paste")
			(net "P1V25_SERDES_VDDPLL_PEX0")
		)
		(pad "2" smd rect
			(at -0.2667 0 270)
			(size 0.3048 0.381)
			(layers "B.Cu" "B.Mask" "B.Paste")
			(net "GND")
		)
	)
	(footprint ""
		(layer "B.Cu")
		(at 69.149976 -300.174914 180)
		(property "Reference" "C3013"
			(at 0 0 0)
			(layer "B.SilkS")
			(hide yes)
			(effects
				(font
					(size 1.27 1.27)
				)
				(justify mirror)
			)
		)
		(property "Value" ""
			(at 0 0 0)
			(layer "B.Fab")
			(effects
				(font
					(size 1.27 1.27)
				)
				(justify mirror)
			)
		)
		(duplicate_pad_numbers_are_jumpers no)
		(fp_line
			(start 0.299974 0.150114)
			(end 0.299974 -0.150114)
			(stroke
				(width 0.1)
				(type default)
			)
			(layer "B.Fab")
		)
		(fp_line
			(start 0.299974 -0.150114)
			(end -0.299974 -0.150114)
			(stroke
				(width 0.1)
				(type default)
			)
			(layer "B.Fab")
		)
		(fp_line
			(start -0.299974 0.150114)
			(end 0.299974 0.150114)
			(stroke
				(width 0.1)
				(type default)
			)
			(layer "B.Fab")
		)
		(fp_line
			(start -0.299974 -0.150114)
			(end -0.299974 0.150114)
			(stroke
				(width 0.1)
				(type default)
			)
			(layer "B.Fab")
		)
		(pad "1" smd rect
			(at 0.2667 0)
			(size 0.3048 0.381)
			(layers "B.Cu" "B.Mask" "B.Paste")
			(net "P1V8_VDDA_PEX0")
		)
		(pad "2" smd rect
			(at -0.2667 0)
			(size 0.3048 0.381)
			(layers "B.Cu" "B.Mask" "B.Paste")
			(net "GND")
		)
	)
	(footprint ""
		(layer "B.Cu")
		(at 341.905082 -285.559754 -90)
		(property "Reference" "PR7179"
			(at 0 0 90)
			(layer "B.SilkS")
			(hide yes)
			(effects
				(font
					(size 1.27 1.27)
				)
				(justify mirror)
			)
		)
		(property "Value" ""
			(at 0 0 90)
			(layer "B.Fab")
			(effects
				(font
					(size 1.27 1.27)
				)
				(justify mirror)
			)
		)
		(duplicate_pad_numbers_are_jumpers no)
		(fp_line
			(start -0.7874 0.4064)
			(end 0.7874 0.4064)
			(stroke
				(width 0.1524)
				(type default)
			)
			(layer "B.SilkS")
		)
		(fp_line
			(start 0.7874 0.4064)
			(end 0.7874 -0.4064)
			(stroke
				(width 0.1524)
				(type default)
			)
			(layer "B.SilkS")
		)
		(fp_line
			(start -0.7874 -0.4064)
			(end -0.7874 0.4064)
			(stroke
				(width 0.1524)
				(type default)
			)
			(layer "B.SilkS")
		)
		(fp_line
			(start 0.7874 -0.4064)
			(end -0.7874 -0.4064)
			(stroke
				(width 0.1524)
				(type default)
			)
			(layer "B.SilkS")
		)
		(fp_line
			(start -0.67945 0.3048)
			(end -0.120396 0.3048)
			(stroke
				(width 0.1)
				(type default)
			)
			(layer "B.Fab")
		)
		(fp_line
			(start -0.120396 0.3048)
			(end -0.120396 0.2794)
			(stroke
				(width 0.1)
				(type default)
			)
			(layer "B.Fab")
		)
		(fp_line
			(start 0.12065 0.3048)
			(end 0.67945 0.3048)
			(stroke
				(width 0.1)
				(type default)
			)
			(layer "B.Fab")
		)
		(fp_line
			(start 0.67945 0.3048)
			(end 0.67945 -0.305054)
			(stroke
				(width 0.1)
				(type default)
			)
			(layer "B.Fab")
		)
		(fp_line
			(start -0.120396 0.2794)
			(end 0.12065 0.2794)
			(stroke
				(width 0.1)
				(type default)
			)
			(layer "B.Fab")
		)
		(fp_line
			(start 0.12065 0.2794)
			(end 0.12065 0.3048)
			(stroke
				(width 0.1)
				(type default)
			)
			(layer "B.Fab")
		)
		(fp_line
			(start -0.12065 -0.2794)
			(end -0.12065 -0.3048)
			(stroke
				(width 0.1)
				(type default)
			)
			(layer "B.Fab")
		)
		(fp_line
			(start 0.12065 -0.2794)
			(end -0.12065 -0.2794)
			(stroke
				(width 0.1)
				(type default)
			)
			(layer "B.Fab")
		)
		(fp_line
			(start -0.67945 -0.3048)
			(end -0.67945 0.3048)
			(stroke
				(width 0.1)
				(type default)
			)
			(layer "B.Fab")
		)
		(fp_line
			(start -0.12065 -0.3048)
			(end -0.67945 -0.3048)
			(stroke
				(width 0.1)
				(type default)
			)
			(layer "B.Fab")
		)
		(fp_line
			(start 0.12065 -0.305054)
			(end 0.12065 -0.2794)
			(stroke
				(width 0.1)
				(type default)
			)
			(layer "B.Fab")
		)
		(fp_line
			(start 0.67945 -0.305054)
			(end 0.12065 -0.305054)
			(stroke
				(width 0.1)
				(type default)
			)
			(layer "B.Fab")
		)
		(pad "1" smd circle
			(at 0.40005 0 90)
			(size 0 0)
			(layers "B.Cu" "B.Mask" "B.Paste")
			(net "P0V8_PEX2_PVCC")
		)
		(pad "2" smd circle
			(at -0.40005 0 90)
			(size 0 0)
			(layers "B.Cu" "B.Mask" "B.Paste")
			(net "P3V3_AUX")
		)
	)
)
